(kicad_pcb
	(version 20260206)
	(generator "pcbnew")
	(generator_version "10.0")
	(general
		(thickness 1.6)
		(legacy_teardrops no)
	)
	(paper "A4")
	(title_block
		(title "01162023_DA0F0TEBIF0_F0T_Expander_BD_F_brd_V02_OCP.brd")
		(comment 1 "Grand Teton / footprints 34-37 of 9728")
	)
	(layers
		(0 "F.Cu" signal "TOP")
		(4 "In1.Cu" signal "GND")
		(6 "In2.Cu" signal "VCC")
		(8 "In3.Cu" signal "VCC1")
		(10 "In4.Cu" signal "GND1")
		(12 "In5.Cu" signal "IN1")
		(14 "In6.Cu" signal "GND2")
		(16 "In7.Cu" signal "IN2")
		(18 "In8.Cu" signal "GND3")
		(20 "In9.Cu" signal "IN3")
		(22 "In10.Cu" signal "GND4")
		(24 "In11.Cu" signal "IN4")
		(26 "In12.Cu" signal "GND5")
		(28 "In13.Cu" signal "IN5")
		(30 "In14.Cu" signal "GND6")
		(32 "In15.Cu" signal "IN6")
		(34 "In16.Cu" signal "GND7")
		(2 "B.Cu" signal "BOTTOM")
		(9 "F.Adhes" user "F.Adhesive")
		(11 "B.Adhes" user "B.Adhesive")
		(13 "F.Paste" user "Package Geometry/Pastemask Top")
		(15 "B.Paste" user "Package Geometry/Pastemask Bottom")
		(5 "F.SilkS" user "Ref Des/Silkscreen Top")
		(7 "B.SilkS" user "Ref Des/Silkscreen Bottom")
		(1 "F.Mask" user "Board Geometry/Soldermask Top")
		(3 "B.Mask" user "Board Geometry/Soldermask Bottom")
		(17 "Dwgs.User" user "User.Drawings")
		(19 "Cmts.User" user "User.Comments")
		(21 "Eco1.User" user "User.Eco1")
		(23 "Eco2.User" user "User.Eco2")
		(25 "Edge.Cuts" user "Board Geometry/Outline")
		(27 "Margin" user)
		(31 "F.CrtYd" user "Package Geometry/Place Bound Top")
		(29 "B.CrtYd" user "Package Geometry/Place Bound Bottom")
		(35 "F.Fab" user "Ref Des/Assembly Top")
		(33 "B.Fab" user "Ref Des/Assembly Bottom")
	)
	(footprint ""
		(layer "F.Cu")
		(at 104.243632 -46.90491)
		(property "Reference" "R541"
			(at 0 0 0)
			(layer "F.SilkS")
			(hide yes)
			(effects
				(font
					(size 1.27 1.27)
				)
			)
		)
		(property "Value" ""
			(at 0 0 0)
			(layer "F.Fab")
			(effects
				(font
					(size 1.27 1.27)
				)
			)
		)
		(duplicate_pad_numbers_are_jumpers no)
		(fp_line
			(start -0.7874 -0.4064)
			(end 0.7874 -0.4064)
			(stroke
				(width 0.1524)
				(type default)
			)
			(layer "F.SilkS")
		)
		(fp_line
			(start -0.7874 0.4064)
			(end -0.7874 -0.4064)
			(stroke
				(width 0.1524)
				(type default)
			)
			(layer "F.SilkS")
		)
		(fp_line
			(start 0.7874 -0.4064)
			(end 0.7874 0.4064)
			(stroke
				(width 0.1524)
				(type default)
			)
			(layer "F.SilkS")
		)
		(fp_line
			(start 0.7874 0.4064)
			(end -0.7874 0.4064)
			(stroke
				(width 0.1524)
				(type default)
			)
			(layer "F.SilkS")
		)
		(fp_line
			(start -0.67945 -0.305054)
			(end -0.12065 -0.305054)
			(stroke
				(width 0.1)
				(type default)
			)
			(layer "F.Fab")
		)
		(fp_line
			(start -0.67945 0.3048)
			(end -0.67945 -0.305054)
			(stroke
				(width 0.1)
				(type default)
			)
			(layer "F.Fab")
		)
		(fp_line
			(start -0.12065 -0.305054)
			(end -0.12065 -0.2794)
			(stroke
				(width 0.1)
				(type default)
			)
			(layer "F.Fab")
		)
		(fp_line
			(start -0.12065 -0.2794)
			(end 0.12065 -0.2794)
			(stroke
				(width 0.1)
				(type default)
			)
			(layer "F.Fab")
		)
		(fp_line
			(start -0.12065 0.2794)
			(end -0.12065 0.3048)
			(stroke
				(width 0.1)
				(type default)
			)
			(layer "F.Fab")
		)
		(fp_line
			(start -0.12065 0.3048)
			(end -0.67945 0.3048)
			(stroke
				(width 0.1)
				(type default)
			)
			(layer "F.Fab")
		)
		(fp_line
			(start 0.120396 0.2794)
			(end -0.12065 0.2794)
			(stroke
				(width 0.1)
				(type default)
			)
			(layer "F.Fab")
		)
		(fp_line
			(start 0.120396 0.3048)
			(end 0.120396 0.2794)
			(stroke
				(width 0.1)
				(type default)
			)
			(layer "F.Fab")
		)
		(fp_line
			(start 0.12065 -0.3048)
			(end 0.67945 -0.3048)
			(stroke
				(width 0.1)
				(type default)
			)
			(layer "F.Fab")
		)
		(fp_line
			(start 0.12065 -0.2794)
			(end 0.12065 -0.3048)
			(stroke
				(width 0.1)
				(type default)
			)
			(layer "F.Fab")
		)
		(fp_line
			(start 0.67945 -0.3048)
			(end 0.67945 0.3048)
			(stroke
				(width 0.1)
				(type default)
			)
			(layer "F.Fab")
		)
		(fp_line
			(start 0.67945 0.3048)
			(end 0.120396 0.3048)
			(stroke
				(width 0.1)
				(type default)
			)
			(layer "F.Fab")
		)
		(pad "1" smd circle
			(at -0.40005 0)
			(size 0 0)
			(layers "F.Cu" "F.Mask" "F.Paste")
			(net "SSD3_ADC_ALERT_N")
		)
		(pad "2" smd circle
			(at 0.40005 0)
			(size 0 0)
			(layers "F.Cu" "F.Mask" "F.Paste")
			(net "SSD_0_7_ADC_ALERT_N")
		)
	)
	(footprint ""
		(layer "F.Cu")
		(at 358.542844 -392.418316 -90)
		(property "Reference" "R6698"
			(at 0 0 270)
			(layer "F.SilkS")
			(hide yes)
			(effects
				(font
					(size 1.27 1.27)
				)
			)
		)
		(property "Value" ""
			(at 0 0 270)
			(layer "F.Fab")
			(effects
				(font
					(size 1.27 1.27)
				)
			)
		)
		(duplicate_pad_numbers_are_jumpers no)
		(fp_line
			(start -0.7874 0.4064)
			(end -0.7874 -0.4064)
			(stroke
				(width 0.1524)
				(type default)
			)
			(layer "F.SilkS")
		)
		(fp_line
			(start 0.7874 0.4064)
			(end -0.7874 0.4064)
			(stroke
				(width 0.1524)
				(type default)
			)
			(layer "F.SilkS")
		)
		(fp_line
			(start -0.7874 -0.4064)
			(end 0.7874 -0.4064)
			(stroke
				(width 0.1524)
				(type default)
			)
			(layer "F.SilkS")
		)
		(fp_line
			(start 0.7874 -0.4064)
			(end 0.7874 0.4064)
			(stroke
				(width 0.1524)
				(type default)
			)
			(layer "F.SilkS")
		)
		(fp_line
			(start -0.67945 0.3048)
			(end -0.67945 -0.305054)
			(stroke
				(width 0.1)
				(type default)
			)
			(layer "F.Fab")
		)
		(fp_line
			(start -0.12065 0.3048)
			(end -0.67945 0.3048)
			(stroke
				(width 0.1)
				(type default)
			)
			(layer "F.Fab")
		)
		(fp_line
			(start 0.120396 0.3048)
			(end 0.120396 0.2794)
			(stroke
				(width 0.1)
				(type default)
			)
			(layer "F.Fab")
		)
		(fp_line
			(start 0.67945 0.3048)
			(end 0.120396 0.3048)
			(stroke
				(width 0.1)
				(type default)
			)
			(layer "F.Fab")
		)
		(fp_line
			(start -0.12065 0.2794)
			(end -0.12065 0.3048)
			(stroke
				(width 0.1)
				(type default)
			)
			(layer "F.Fab")
		)
		(fp_line
			(start 0.120396 0.2794)
			(end -0.12065 0.2794)
			(stroke
				(width 0.1)
				(type default)
			)
			(layer "F.Fab")
		)
		(fp_line
			(start -0.12065 -0.2794)
			(end 0.12065 -0.2794)
			(stroke
				(width 0.1)
				(type default)
			)
			(layer "F.Fab")
		)
		(fp_line
			(start 0.12065 -0.2794)
			(end 0.12065 -0.3048)
			(stroke
				(width 0.1)
				(type default)
			)
			(layer "F.Fab")
		)
		(fp_line
			(start 0.12065 -0.3048)
			(end 0.67945 -0.3048)
			(stroke
				(width 0.1)
				(type default)
			)
			(layer "F.Fab")
		)
		(fp_line
			(start 0.67945 -0.3048)
			(end 0.67945 0.3048)
			(stroke
				(width 0.1)
				(type default)
			)
			(layer "F.Fab")
		)
		(fp_line
			(start -0.67945 -0.305054)
			(end -0.12065 -0.305054)
			(stroke
				(width 0.1)
				(type default)
			)
			(layer "F.Fab")
		)
		(fp_line
			(start -0.12065 -0.305054)
			(end -0.12065 -0.2794)
			(stroke
				(width 0.1)
				(type default)
			)
			(layer "F.Fab")
		)
		(pad "1" smd circle
			(at -0.40005 0 270)
			(size 0 0)
			(layers "F.Cu" "F.Mask" "F.Paste")
			(net "MB_3V3IO_RSVD1_ISO_R")
		)
		(pad "2" smd circle
			(at 0.40005 0 270)
			(size 0 0)
			(layers "F.Cu" "F.Mask" "F.Paste")
			(net "MB_3V3IO_RSVD1_ISO")
		)
	)
	(footprint ""
		(layer "F.Cu")
		(at 207.734408 -310.478932 -45)
		(property "Reference" "R3944"
			(at 0 0 315)
			(layer "F.SilkS")
			(hide yes)
			(effects
				(font
					(size 1.27 1.27)
				)
			)
		)
		(property "Value" ""
			(at 0 0 315)
			(layer "F.Fab")
			(effects
				(font
					(size 1.27 1.27)
				)
			)
		)
		(duplicate_pad_numbers_are_jumpers no)
		(fp_line
			(start -0.787389 0.406267)
			(end -0.787389 -0.406267)
			(stroke
				(width 0.1524)
				(type default)
			)
			(layer "F.SilkS")
		)
		(fp_line
			(start -0.787389 -0.406267)
			(end 0.787389 -0.406267)
			(stroke
				(width 0.1524)
				(type default)
			)
			(layer "F.SilkS")
		)
		(fp_line
			(start 0.787389 0.406267)
			(end -0.787389 0.406267)
			(stroke
				(width 0.1524)
				(type default)
			)
			(layer "F.SilkS")
		)
		(fp_line
			(start 0.787389 -0.406267)
			(end 0.787389 0.406267)
			(stroke
				(width 0.1524)
				(type default)
			)
			(layer "F.SilkS")
		)
		(fp_line
			(start -0.679446 0.30479)
			(end -0.679446 -0.305149)
			(stroke
				(width 0.1)
				(type default)
			)
			(layer "F.Fab")
		)
		(fp_line
			(start -0.120515 0.30479)
			(end -0.679446 0.30479)
			(stroke
				(width 0.1)
				(type default)
			)
			(layer "F.Fab")
		)
		(fp_line
			(start -0.120695 0.279466)
			(end -0.120515 0.30479)
			(stroke
				(width 0.1)
				(type default)
			)
			(layer "F.Fab")
		)
		(fp_line
			(start -0.679446 -0.305149)
			(end -0.120695 -0.304969)
			(stroke
				(width 0.1)
				(type default)
			)
			(layer "F.Fab")
		)
		(fp_line
			(start 0.120515 0.30479)
			(end 0.120335 0.279466)
			(stroke
				(width 0.1)
				(type default)
			)
			(layer "F.Fab")
		)
		(fp_line
			(start 0.120335 0.279466)
			(end -0.120695 0.279466)
			(stroke
				(width 0.1)
				(type default)
			)
			(layer "F.Fab")
		)
		(fp_line
			(start -0.120695 -0.279466)
			(end 0.120695 -0.279466)
			(stroke
				(width 0.1)
				(type default)
			)
			(layer "F.Fab")
		)
		(fp_line
			(start -0.120695 -0.304969)
			(end -0.120695 -0.279466)
			(stroke
				(width 0.1)
				(type default)
			)
			(layer "F.Fab")
		)
		(fp_line
			(start 0.679446 0.30479)
			(end 0.120515 0.30479)
			(stroke
				(width 0.1)
				(type default)
			)
			(layer "F.Fab")
		)
		(fp_line
			(start 0.120695 -0.279466)
			(end 0.120515 -0.30479)
			(stroke
				(width 0.1)
				(type default)
			)
			(layer "F.Fab")
		)
		(fp_line
			(start 0.120515 -0.30479)
			(end 0.679446 -0.30479)
			(stroke
				(width 0.1)
				(type default)
			)
			(layer "F.Fab")
		)
		(fp_line
			(start 0.679446 -0.30479)
			(end 0.679446 0.30479)
			(stroke
				(width 0.1)
				(type default)
			)
			(layer "F.Fab")
		)
		(pad "1" smd circle
			(at -0.40005 0 315)
			(size 0 0)
			(layers "F.Cu" "F.Mask" "F.Paste")
			(net "PU_PEX1_SIO_BLINK")
		)
		(pad "2" smd circle
			(at 0.40005 0 315)
			(size 0 0)
			(layers "F.Cu" "F.Mask" "F.Paste")
			(net "P1V8_PEX")
		)
	)
	(footprint ""
		(layer "F.Cu")
		(at 352.920554 -91.788234 180)
		(property "Reference" "R1607"
			(at 0 0 180)
			(layer "F.SilkS")
			(hide yes)
			(effects
				(font
					(size 1.27 1.27)
				)
			)
		)
		(property "Value" ""
			(at 0 0 180)
			(layer "F.Fab")
			(effects
				(font
					(size 1.27 1.27)
				)
			)
		)
		(duplicate_pad_numbers_are_jumpers no)
		(fp_line
			(start 0.7874 0.4064)
			(end -0.7874 0.4064)
			(stroke
				(width 0.1524)
				(type default)
			)
			(layer "F.SilkS")
		)
		(fp_line
			(start 0.7874 -0.4064)
			(end 0.7874 0.4064)
			(stroke
				(width 0.1524)
				(type default)
			)
			(layer "F.SilkS")
		)
		(fp_line
			(start -0.7874 0.4064)
			(end -0.7874 -0.4064)
			(stroke
				(width 0.1524)
				(type default)
			)
			(layer "F.SilkS")
		)
		(fp_line
			(start -0.7874 -0.4064)
			(end 0.7874 -0.4064)
			(stroke
				(width 0.1524)
				(type default)
			)
			(layer "F.SilkS")
		)
		(fp_line
			(start 0.67945 0.3048)
			(end 0.120396 0.3048)
			(stroke
				(width 0.1)
				(type default)
			)
			(layer "F.Fab")
		)
		(fp_line
			(start 0.67945 -0.3048)
			(end 0.67945 0.3048)
			(stroke
				(width 0.1)
				(type default)
			)
			(layer "F.Fab")
		)
		(fp_line
			(start 0.12065 -0.2794)
			(end 0.12065 -0.3048)
			(stroke
				(width 0.1)
				(type default)
			)
			(layer "F.Fab")
		)
		(fp_line
			(start 0.12065 -0.3048)
			(end 0.67945 -0.3048)
			(stroke
				(width 0.1)
				(type default)
			)
			(layer "F.Fab")
		)
		(fp_line
			(start 0.120396 0.3048)
			(end 0.120396 0.2794)
			(stroke
				(width 0.1)
				(type default)
			)
			(layer "F.Fab")
		)
		(fp_line
			(start 0.120396 0.2794)
			(end -0.12065 0.2794)
			(stroke
				(width 0.1)
				(type default)
			)
			(layer "F.Fab")
		)
		(fp_line
			(start -0.12065 0.3048)
			(end -0.67945 0.3048)
			(stroke
				(width 0.1)
				(type default)
			)
			(layer "F.Fab")
		)
		(fp_line
			(start -0.12065 0.2794)
			(end -0.12065 0.3048)
			(stroke
				(width 0.1)
				(type default)
			)
			(layer "F.Fab")
		)
		(fp_line
			(start -0.12065 -0.2794)
			(end 0.12065 -0.2794)
			(stroke
				(width 0.1)
				(type default)
			)
			(layer "F.Fab")
		)
		(fp_line
			(start -0.12065 -0.305054)
			(end -0.12065 -0.2794)
			(stroke
				(width 0.1)
				(type default)
			)
			(layer "F.Fab")
		)
		(fp_line
			(start -0.67945 0.3048)
			(end -0.67945 -0.305054)
			(stroke
				(width 0.1)
				(type default)
			)
			(layer "F.Fab")
		)
		(fp_line
			(start -0.67945 -0.305054)
			(end -0.12065 -0.305054)
			(stroke
				(width 0.1)
				(type default)
			)
			(layer "F.Fab")
		)
		(pad "1" smd circle
			(at -0.40005 0 180)
			(size 0 0)
			(layers "F.Cu" "F.Mask" "F.Paste")
			(net "BIC_I2C9_SSD_MUX1_A0")
		)
		(pad "2" smd circle
			(at 0.40005 0 180)
			(size 0 0)
			(layers "F.Cu" "F.Mask" "F.Paste")
			(net "GND")
		)
	)
)
